# T6G (Grand Teton) — schematic netlist excerpt (pin names and nets, part order shuffled) for the footprints in the layout excerpt that follows; sources: Cadence DE-HDL packaged netlist, KiCad conversion of 04192023_DAF0TMB3IC0_F0TG_MB_C_brd_V02_OCP.brd

PC184  Q_CAP  560PF 50V 10% EMPTY  pkg C0402  page 196 : A = SW_PVDDCR_CPU0_P0_SW5 ; B = SW_PVDDCR_CPU0_P0_SW5_RC
R955  Q_RES  0 5% CHIP  pkg 0402LF  page 145 : A = FM_LED_ACTIVE_E1S_0 ; B = FM_LED_ACTIVE_E1S_0_R

(kicad_pcb
	(version 20260206)
	(generator "pcbnew")
	(generator_version "10.0")
	(general
		(thickness 1.6)
		(legacy_teardrops no)
	)
	(paper "A4")
	(title_block
		(title "04192023_DAF0TMB3IC0_F0TG_MB_C_brd_V02_OCP.brd")
		(comment 1 "Grand Teton / footprints 2068-2069 of 8354")
	)
	(layers
		(0 "F.Cu" signal "TOP")
		(4 "In1.Cu" signal "GND")
		(6 "In2.Cu" signal "IN1")
		(8 "In3.Cu" signal "GND1")
		(10 "In4.Cu" signal "IN2")
		(12 "In5.Cu" signal "GND2")
		(14 "In6.Cu" signal "IN3")
		(16 "In7.Cu" signal "GND3")
		(18 "In8.Cu" signal "VCC")
		(20 "In9.Cu" signal "VCC1")
		(22 "In10.Cu" signal "GND4")
		(24 "In11.Cu" signal "IN4")
		(26 "In12.Cu" signal "GND5")
		(28 "In13.Cu" signal "IN5")
		(30 "In14.Cu" signal "GND6")
		(32 "In15.Cu" signal "IN6")
		(34 "In16.Cu" signal "GND7")
		(2 "B.Cu" signal "BOTTOM")
		(9 "F.Adhes" user "F.Adhesive")
		(11 "B.Adhes" user "B.Adhesive")
		(13 "F.Paste" user "Package Geometry/Pastemask Top")
		(15 "B.Paste" user "Package Geometry/Pastemask Bottom")
		(5 "F.SilkS" user "Ref Des/Silkscreen Top")
		(7 "B.SilkS" user "Ref Des/Silkscreen Bottom")
		(1 "F.Mask" user "Board Geometry/Soldermask Top")
		(3 "B.Mask" user "Board Geometry/Soldermask Bottom")
		(17 "Dwgs.User" user "User.Drawings")
		(19 "Cmts.User" user "User.Comments")
		(21 "Eco1.User" user "User.Eco1")
		(23 "Eco2.User" user "User.Eco2")
		(25 "Edge.Cuts" user "Board Geometry/Outline")
		(27 "Margin" user)
		(31 "F.CrtYd" user "Package Geometry/Place Bound Top")
		(29 "B.CrtYd" user "Package Geometry/Place Bound Bottom")
		(35 "F.Fab" user "Ref Des/Assembly Top")
		(33 "B.Fab" user "Ref Des/Assembly Bottom")
	)
	(footprint ""
		(layer "F.Cu")
		(at 241.112802 -70.143624 -90)
		(property "Reference" "R955"
			(at 0 0 270)
			(layer "F.SilkS")
			(hide yes)
			(effects
				(font
					(size 1.27 1.27)
				)
			)
		)
		(property "Value" ""
			(at 0 0 270)
			(layer "F.Fab")
			(effects
				(font
					(size 1.27 1.27)
				)
			)
		)
		(duplicate_pad_numbers_are_jumpers no)
		(fp_line
			(start -0.7874 0.4064)
			(end -0.7874 -0.4064)
			(stroke
				(width 0.1524)
				(type default)
			)
			(layer "F.SilkS")
		)
		(fp_line
			(start 0.7874 0.4064)
			(end -0.7874 0.4064)
			(stroke
				(width 0.1524)
				(type default)
			)
			(layer "F.SilkS")
		)
		(fp_line
			(start -0.7874 -0.4064)
			(end 0.7874 -0.4064)
			(stroke
				(width 0.1524)
				(type default)
			)
			(layer "F.SilkS")
		)
		(fp_line
			(start 0.7874 -0.4064)
			(end 0.7874 0.4064)
			(stroke
				(width 0.1524)
				(type default)
			)
			(layer "F.SilkS")
		)
		(fp_line
			(start -0.67945 0.3048)
			(end -0.67945 -0.305054)
			(stroke
				(width 0.1)
				(type default)
			)
			(layer "F.Fab")
		)
		(fp_line
			(start -0.12065 0.3048)
			(end -0.67945 0.3048)
			(stroke
				(width 0.1)
				(type default)
			)
			(layer "F.Fab")
		)
		(fp_line
			(start 0.120396 0.3048)
			(end 0.120396 0.2794)
			(stroke
				(width 0.1)
				(type default)
			)
			(layer "F.Fab")
		)
		(fp_line
			(start 0.67945 0.3048)
			(end 0.120396 0.3048)
			(stroke
				(width 0.1)
				(type default)
			)
			(layer "F.Fab")
		)
		(fp_line
			(start -0.12065 0.2794)
			(end -0.12065 0.3048)
			(stroke
				(width 0.1)
				(type default)
			)
			(layer "F.Fab")
		)
		(fp_line
			(start 0.120396 0.2794)
			(end -0.12065 0.2794)
			(stroke
				(width 0.1)
				(type default)
			)
			(layer "F.Fab")
		)
		(fp_line
			(start -0.12065 -0.2794)
			(end 0.12065 -0.2794)
			(stroke
				(width 0.1)
				(type default)
			)
			(layer "F.Fab")
		)
		(fp_line
			(start 0.12065 -0.2794)
			(end 0.12065 -0.3048)
			(stroke
				(width 0.1)
				(type default)
			)
			(layer "F.Fab")
		)
		(fp_line
			(start 0.12065 -0.3048)
			(end 0.67945 -0.3048)
			(stroke
				(width 0.1)
				(type default)
			)
			(layer "F.Fab")
		)
		(fp_line
			(start 0.67945 -0.3048)
			(end 0.67945 0.3048)
			(stroke
				(width 0.1)
				(type default)
			)
			(layer "F.Fab")
		)
		(fp_line
			(start -0.67945 -0.305054)
			(end -0.12065 -0.305054)
			(stroke
				(width 0.1)
				(type default)
			)
			(layer "F.Fab")
		)
		(fp_line
			(start -0.12065 -0.305054)
			(end -0.12065 -0.2794)
			(stroke
				(width 0.1)
				(type default)
			)
			(layer "F.Fab")
		)
		(pad "1" smd circle
			(at -0.40005 0 270)
			(size 0 0)
			(layers "F.Cu" "F.Mask" "F.Paste")
			(net "FM_LED_ACTIVE_E1S_0")
		)
		(pad "2" smd circle
			(at 0.40005 0 270)
			(size 0 0)
			(layers "F.Cu" "F.Mask" "F.Paste")
			(net "FM_LED_ACTIVE_E1S_0_R")
		)
	)
	(footprint ""
		(layer "F.Cu")
		(at 359.7275 -172.50029)
		(property "Reference" "PC184"
			(at 0 0 0)
			(layer "F.SilkS")
			(hide yes)
			(effects
				(font
					(size 1.27 1.27)
				)
			)
		)
		(property "Value" ""
			(at 0 0 0)
			(layer "F.Fab")
			(effects
				(font
					(size 1.27 1.27)
				)
			)
		)
		(duplicate_pad_numbers_are_jumpers no)
		(fp_line
			(start -0.7874 -0.4064)
			(end 0.7874 -0.4064)
			(stroke
				(width 0.1524)
				(type default)
			)
			(layer "F.SilkS")
		)
		(fp_line
			(start -0.7874 0.4064)
			(end -0.7874 -0.4064)
			(stroke
				(width 0.1524)
				(type default)
			)
			(layer "F.SilkS")
		)
		(fp_line
			(start 0.7874 -0.4064)
			(end 0.7874 0.4064)
			(stroke
				(width 0.1524)
				(type default)
			)
			(layer "F.SilkS")
		)
		(fp_line
			(start 0.7874 0.4064)
			(end -0.7874 0.4064)
			(stroke
				(width 0.1524)
				(type default)
			)
			(layer "F.SilkS")
		)
		(fp_line
			(start -0.67945 -0.305054)
			(end -0.12065 -0.305054)
			(stroke
				(width 0.1)
				(type default)
			)
			(layer "F.Fab")
		)
		(fp_line
			(start -0.67945 0.3048)
			(end -0.67945 -0.305054)
			(stroke
				(width 0.1)
				(type default)
			)
			(layer "F.Fab")
		)
		(fp_line
			(start -0.12065 -0.305054)
			(end -0.12065 -0.2794)
			(stroke
				(width 0.1)
				(type default)
			)
			(layer "F.Fab")
		)
		(fp_line
			(start -0.12065 -0.2794)
			(end 0.12065 -0.2794)
			(stroke
				(width 0.1)
				(type default)
			)
			(layer "F.Fab")
		)
		(fp_line
			(start -0.12065 0.2794)
			(end -0.12065 0.3048)
			(stroke
				(width 0.1)
				(type default)
			)
			(layer "F.Fab")
		)
		(fp_line
			(start -0.12065 0.3048)
			(end -0.67945 0.3048)
			(stroke
				(width 0.1)
				(type default)
			)
			(layer "F.Fab")
		)
		(fp_line
			(start 0.120396 0.2794)
			(end -0.12065 0.2794)
			(stroke
				(width 0.1)
				(type default)
			)
			(layer "F.Fab")
		)
		(fp_line
			(start 0.120396 0.3048)
			(end 0.120396 0.2794)
			(stroke
				(width 0.1)
				(type default)
			)
			(layer "F.Fab")
		)
		(fp_line
			(start 0.12065 -0.3048)
			(end 0.67945 -0.3048)
			(stroke
				(width 0.1)
				(type default)
			)
			(layer "F.Fab")
		)
		(fp_line
			(start 0.12065 -0.2794)
			(end 0.12065 -0.3048)
			(stroke
				(width 0.1)
				(type default)
			)
			(layer "F.Fab")
		)
		(fp_line
			(start 0.67945 -0.3048)
			(end 0.67945 0.3048)
			(stroke
				(width 0.1)
				(type default)
			)
			(layer "F.Fab")
		)
		(fp_line
			(start 0.67945 0.3048)
			(end 0.120396 0.3048)
			(stroke
				(width 0.1)
				(type default)
			)
			(layer "F.Fab")
		)
		(pad "1" smd circle
			(at -0.40005 0)
			(size 0 0)
			(layers "F.Cu" "F.Mask" "F.Paste")
			(net "SW_PVDDCR_CPU0_P0_SW5")
		)
		(pad "2" smd circle
			(at 0.40005 0)
			(size 0 0)
			(layers "F.Cu" "F.Mask" "F.Paste")
			(net "SW_PVDDCR_CPU0_P0_SW5_RC")
		)
	)
)
